# discovery-power-board-v1-revB — fixing_hole.kicad_mod (kicad-footprint)
(module fixing_hole (layer F.Cu) 
  (fp_text reference REF** (at -4.4323 -7.4676) (layer F.SilkS)
    (effects (font (size 1 1) (thickness 0.15)))
  )
  (fp_text value fixing_hole (at 5.3721 8.3312) (layer F.Fab)
    (effects (font (size 1 1) (thickness 0.15)))
  )
  (fp_circle (center 0 0) (end 7.6 0) (layer F.CrtYd) (width 0.1))
  (pad 1 thru_hole circle (at 0 0) (size 15 15) (drill 5.7) (layers *.Cu *.Mask F.SilkS))
)
